(kicad_pcb
	(version 20260206)
	(generator "pcbnew")
	(generator_version "10.0")
	(general
		(thickness 1.6)
		(legacy_teardrops no)
	)
	(paper "A4")
	(title_block
		(title "03242023_DA0F0TMBIJ0_F0T_Motherboard_J_brd_V01_OCP.brd")
		(comment 1 "Grand Teton / footprint 1368 of 6105 (J13), pads 1-112 of 291")
	)
	(layers
		(0 "F.Cu" signal "TOP")
		(4 "In1.Cu" signal "GND")
		(6 "In2.Cu" signal "IN1")
		(8 "In3.Cu" signal "GND1")
		(10 "In4.Cu" signal "IN2")
		(12 "In5.Cu" signal "GND2")
		(14 "In6.Cu" signal "IN3")
		(16 "In7.Cu" signal "GND3")
		(18 "In8.Cu" signal "VCC")
		(20 "In9.Cu" signal "VCC1")
		(22 "In10.Cu" signal "GND4")
		(24 "In11.Cu" signal "IN4")
		(26 "In12.Cu" signal "GND5")
		(28 "In13.Cu" signal "IN5")
		(30 "In14.Cu" signal "GND6")
		(32 "In15.Cu" signal "IN6")
		(34 "In16.Cu" signal "GND7")
		(2 "B.Cu" signal "BOTTOM")
		(9 "F.Adhes" user "F.Adhesive")
		(11 "B.Adhes" user "B.Adhesive")
		(13 "F.Paste" user "Package Geometry/Pastemask Top")
		(15 "B.Paste" user "Package Geometry/Pastemask Bottom")
		(5 "F.SilkS" user "Ref Des/Silkscreen Top")
		(7 "B.SilkS" user "Ref Des/Silkscreen Bottom")
		(1 "F.Mask" user "Board Geometry/Soldermask Top")
		(3 "B.Mask" user "Board Geometry/Soldermask Bottom")
		(17 "Dwgs.User" user "User.Drawings")
		(19 "Cmts.User" user "User.Comments")
		(21 "Eco1.User" user "User.Eco1")
		(23 "Eco2.User" user "User.Eco2")
		(25 "Edge.Cuts" user "Board Geometry/Outline")
		(27 "Margin" user)
		(31 "F.CrtYd" user "Package Geometry/Place Bound Top")
		(29 "B.CrtYd" user "Package Geometry/Place Bound Bottom")
		(35 "F.Fab" user "Ref Des/Assembly Top")
		(33 "B.Fab" user "Ref Des/Assembly Bottom")
	)
	(footprint ""
		(layer "F.Cu")
		(at 446.522348 -258.091686)
		(property "Reference" "J13"
			(at -3.683 -81.702148 0)
			(unlocked yes)
			(layer "F.SilkS")
			(effects
				(font
					(size 0.7874 0.5842)
					(thickness 0.1524)
				)
				(justify left)
			)
		)
		(property "Value" ""
			(at 0 0 0)
			(layer "F.Fab")
			(effects
				(font
					(size 1.27 1.27)
				)
			)
		)
		(duplicate_pad_numbers_are_jumpers no)
		(pad "1" smd rect
			(at -2.050034 -63.324994 270)
			(size 0.519938 1.4986)
			(layers "F.Cu" "F.Mask" "F.Paste")
			(net "P12V_S3_AUX_CPU0_NVDIMM")
		)
		(pad "2" smd rect
			(at -2.050034 -62.47511 270)
			(size 0.519938 1.4986)
			(layers "F.Cu" "F.Mask" "F.Paste")
			(net "TP_CHG_CPU0_DIMM1_FRU_0")
		)
		(pad "3" smd rect
			(at -2.050034 -61.624972 270)
			(size 0.519938 1.4986)
			(layers "F.Cu" "F.Mask" "F.Paste")
			(net "P3V3_AUX")
		)
		(pad "4" smd rect
			(at -2.050034 -60.775088 270)
			(size 0.519938 1.4986)
			(layers "F.Cu" "F.Mask" "F.Paste")
			(net "I3C_SPD_DDREFGH_CPU0_LVC1_SCL_4")
		)
		(pad "5" smd rect
			(at -2.050034 -59.92495 270)
			(size 0.519938 1.4986)
			(layers "F.Cu" "F.Mask" "F.Paste")
			(net "I3C_SPD_DDREFGH_CPU0_LVC1_SDA")
		)
		(pad "6" smd rect
			(at -2.050034 -59.075066 270)
			(size 0.519938 1.4986)
			(layers "F.Cu" "F.Mask" "F.Paste")
			(net "GND")
		)
		(pad "7" smd rect
			(at -2.050034 -58.224928 270)
			(size 0.519938 1.4986)
			(layers "F.Cu" "F.Mask" "F.Paste")
			(net "M_G_CPU0_SA_DQ<0>")
		)
		(pad "8" smd rect
			(at -2.050034 -57.375044 270)
			(size 0.519938 1.4986)
			(layers "F.Cu" "F.Mask" "F.Paste")
			(net "GND")
		)
		(pad "9" smd rect
			(at -2.050034 -56.524906 270)
			(size 0.519938 1.4986)
			(layers "F.Cu" "F.Mask" "F.Paste")
			(net "M_G_CPU0_SA_DQ<1>")
		)
		(pad "10" smd rect
			(at -2.050034 -55.675022 270)
			(size 0.519938 1.4986)
			(layers "F.Cu" "F.Mask" "F.Paste")
			(net "GND")
		)
		(pad "11" smd rect
			(at -2.050034 -54.824884 270)
			(size 0.519938 1.4986)
			(layers "F.Cu" "F.Mask" "F.Paste")
			(net "M_G_CPU0_SA_DQS_DP<0>")
		)
		(pad "12" smd rect
			(at -2.050034 -53.975 270)
			(size 0.519938 1.4986)
			(layers "F.Cu" "F.Mask" "F.Paste")
			(net "M_G_CPU0_SA_DQS_DN<0>")
		)
		(pad "13" smd rect
			(at -2.050034 -53.125116 270)
			(size 0.519938 1.4986)
			(layers "F.Cu" "F.Mask" "F.Paste")
			(net "GND")
		)
		(pad "14" smd rect
			(at -2.050034 -52.274978 270)
			(size 0.519938 1.4986)
			(layers "F.Cu" "F.Mask" "F.Paste")
			(net "M_G_CPU0_SA_DQ<4>")
		)
		(pad "15" smd rect
			(at -2.050034 -51.425094 270)
			(size 0.519938 1.4986)
			(layers "F.Cu" "F.Mask" "F.Paste")
			(net "GND")
		)
		(pad "16" smd rect
			(at -2.050034 -50.574956 270)
			(size 0.519938 1.4986)
			(layers "F.Cu" "F.Mask" "F.Paste")
			(net "M_G_CPU0_SA_DQ<5>")
		)
		(pad "17" smd rect
			(at -2.050034 -49.725072 270)
			(size 0.519938 1.4986)
			(layers "F.Cu" "F.Mask" "F.Paste")
			(net "GND")
		)
		(pad "18" smd rect
			(at -2.050034 -48.874934 270)
			(size 0.519938 1.4986)
			(layers "F.Cu" "F.Mask" "F.Paste")
			(net "M_G_CPU0_SA_DQ<8>")
		)
		(pad "19" smd rect
			(at -2.050034 -48.02505 270)
			(size 0.519938 1.4986)
			(layers "F.Cu" "F.Mask" "F.Paste")
			(net "GND")
		)
		(pad "20" smd rect
			(at -2.050034 -47.174912 270)
			(size 0.519938 1.4986)
			(layers "F.Cu" "F.Mask" "F.Paste")
			(net "M_G_CPU0_SA_DQ<9>")
		)
		(pad "21" smd rect
			(at -2.050034 -46.325028 270)
			(size 0.519938 1.4986)
			(layers "F.Cu" "F.Mask" "F.Paste")
			(net "GND")
		)
		(pad "22" smd rect
			(at -2.050034 -45.47489 270)
			(size 0.519938 1.4986)
			(layers "F.Cu" "F.Mask" "F.Paste")
			(net "M_G_CPU0_SA_DQS_DP<1>")
		)
		(pad "23" smd rect
			(at -2.050034 -44.625006 270)
			(size 0.519938 1.4986)
			(layers "F.Cu" "F.Mask" "F.Paste")
			(net "M_G_CPU0_SA_DQS_DN<1>")
		)
		(pad "24" smd rect
			(at -2.050034 -43.775122 270)
			(size 0.519938 1.4986)
			(layers "F.Cu" "F.Mask" "F.Paste")
			(net "GND")
		)
		(pad "25" smd rect
			(at -2.050034 -42.924984 270)
			(size 0.519938 1.4986)
			(layers "F.Cu" "F.Mask" "F.Paste")
			(net "M_G_CPU0_SA_DQ<12>")
		)
		(pad "26" smd rect
			(at -2.050034 -42.0751 270)
			(size 0.519938 1.4986)
			(layers "F.Cu" "F.Mask" "F.Paste")
			(net "GND")
		)
		(pad "27" smd rect
			(at -2.050034 -41.224962 270)
			(size 0.519938 1.4986)
			(layers "F.Cu" "F.Mask" "F.Paste")
			(net "M_G_CPU0_SA_DQ<13>")
		)
		(pad "28" smd rect
			(at -2.050034 -40.375078 270)
			(size 0.519938 1.4986)
			(layers "F.Cu" "F.Mask" "F.Paste")
			(net "GND")
		)
		(pad "29" smd rect
			(at -2.050034 -39.52494 270)
			(size 0.519938 1.4986)
			(layers "F.Cu" "F.Mask" "F.Paste")
			(net "M_G_CPU0_SA_DQ<16>")
		)
		(pad "30" smd rect
			(at -2.050034 -38.675056 270)
			(size 0.519938 1.4986)
			(layers "F.Cu" "F.Mask" "F.Paste")
			(net "GND")
		)
		(pad "31" smd rect
			(at -2.050034 -37.824918 270)
			(size 0.519938 1.4986)
			(layers "F.Cu" "F.Mask" "F.Paste")
			(net "M_G_CPU0_SA_DQ<17>")
		)
		(pad "32" smd rect
			(at -2.050034 -36.975034 270)
			(size 0.519938 1.4986)
			(layers "F.Cu" "F.Mask" "F.Paste")
			(net "GND")
		)
		(pad "33" smd rect
			(at -2.050034 -36.124896 270)
			(size 0.519938 1.4986)
			(layers "F.Cu" "F.Mask" "F.Paste")
			(net "M_G_CPU0_SA_DQS_DP<2>")
		)
		(pad "34" smd rect
			(at -2.050034 -35.275012 270)
			(size 0.519938 1.4986)
			(layers "F.Cu" "F.Mask" "F.Paste")
			(net "M_G_CPU0_SA_DQS_DN<2>")
		)
		(pad "35" smd rect
			(at -2.050034 -34.425128 270)
			(size 0.519938 1.4986)
			(layers "F.Cu" "F.Mask" "F.Paste")
			(net "GND")
		)
		(pad "36" smd rect
			(at -2.050034 -33.57499 270)
			(size 0.519938 1.4986)
			(layers "F.Cu" "F.Mask" "F.Paste")
			(net "M_G_CPU0_SA_DQ<20>")
		)
		(pad "37" smd rect
			(at -2.050034 -32.725106 270)
			(size 0.519938 1.4986)
			(layers "F.Cu" "F.Mask" "F.Paste")
			(net "GND")
		)
		(pad "38" smd rect
			(at -2.050034 -31.874968 270)
			(size 0.519938 1.4986)
			(layers "F.Cu" "F.Mask" "F.Paste")
			(net "M_G_CPU0_SA_DQ<21>")
		)
		(pad "39" smd rect
			(at -2.050034 -31.025084 270)
			(size 0.519938 1.4986)
			(layers "F.Cu" "F.Mask" "F.Paste")
			(net "GND")
		)
		(pad "40" smd rect
			(at -2.050034 -30.174946 270)
			(size 0.519938 1.4986)
			(layers "F.Cu" "F.Mask" "F.Paste")
			(net "M_G_CPU0_SA_DQ<24>")
		)
		(pad "41" smd rect
			(at -2.050034 -29.325062 270)
			(size 0.519938 1.4986)
			(layers "F.Cu" "F.Mask" "F.Paste")
			(net "GND")
		)
		(pad "42" smd rect
			(at -2.050034 -28.474924 270)
			(size 0.519938 1.4986)
			(layers "F.Cu" "F.Mask" "F.Paste")
			(net "M_G_CPU0_SA_DQ<25>")
		)
		(pad "43" smd rect
			(at -2.050034 -27.62504 270)
			(size 0.519938 1.4986)
			(layers "F.Cu" "F.Mask" "F.Paste")
			(net "GND")
		)
		(pad "44" smd rect
			(at -2.050034 -26.774902 270)
			(size 0.519938 1.4986)
			(layers "F.Cu" "F.Mask" "F.Paste")
			(net "M_G_CPU0_SA_DQS_DP<3>")
		)
		(pad "45" smd rect
			(at -2.050034 -25.925018 270)
			(size 0.519938 1.4986)
			(layers "F.Cu" "F.Mask" "F.Paste")
			(net "M_G_CPU0_SA_DQS_DN<3>")
		)
		(pad "46" smd rect
			(at -2.050034 -25.07488 270)
			(size 0.519938 1.4986)
			(layers "F.Cu" "F.Mask" "F.Paste")
			(net "GND")
		)
		(pad "47" smd rect
			(at -2.050034 -24.224996 270)
			(size 0.519938 1.4986)
			(layers "F.Cu" "F.Mask" "F.Paste")
			(net "M_G_CPU0_SA_DQ<28>")
		)
		(pad "48" smd rect
			(at -2.050034 -23.375112 270)
			(size 0.519938 1.4986)
			(layers "F.Cu" "F.Mask" "F.Paste")
			(net "GND")
		)
		(pad "49" smd rect
			(at -2.050034 -22.524974 270)
			(size 0.519938 1.4986)
			(layers "F.Cu" "F.Mask" "F.Paste")
			(net "M_G_CPU0_SA_DQ<29>")
		)
		(pad "50" smd rect
			(at -2.050034 -21.67509 270)
			(size 0.519938 1.4986)
			(layers "F.Cu" "F.Mask" "F.Paste")
			(net "GND")
		)
		(pad "51" smd rect
			(at -2.050034 -20.824952 270)
			(size 0.519938 1.4986)
			(layers "F.Cu" "F.Mask" "F.Paste")
			(net "M_G_CPU0_SA_CB<0>")
		)
		(pad "52" smd rect
			(at -2.050034 -19.975068 270)
			(size 0.519938 1.4986)
			(layers "F.Cu" "F.Mask" "F.Paste")
			(net "GND")
		)
		(pad "53" smd rect
			(at -2.050034 -19.12493 270)
			(size 0.519938 1.4986)
			(layers "F.Cu" "F.Mask" "F.Paste")
			(net "M_G_CPU0_SA_CB<1>")
		)
		(pad "54" smd rect
			(at -2.050034 -18.275046 270)
			(size 0.519938 1.4986)
			(layers "F.Cu" "F.Mask" "F.Paste")
			(net "GND")
		)
		(pad "55" smd rect
			(at -2.050034 -17.424908 270)
			(size 0.519938 1.4986)
			(layers "F.Cu" "F.Mask" "F.Paste")
			(net "M_G_CPU0_SA_DQS_DP<4>")
		)
		(pad "56" smd rect
			(at -2.050034 -16.575024 270)
			(size 0.519938 1.4986)
			(layers "F.Cu" "F.Mask" "F.Paste")
			(net "M_G_CPU0_SA_DQS_DN<4>")
		)
		(pad "57" smd rect
			(at -2.050034 -15.724886 270)
			(size 0.519938 1.4986)
			(layers "F.Cu" "F.Mask" "F.Paste")
			(net "GND")
		)
		(pad "58" smd rect
			(at -2.050034 -14.875002 270)
			(size 0.519938 1.4986)
			(layers "F.Cu" "F.Mask" "F.Paste")
			(net "M_G_CPU0_SA_CB<4>")
		)
		(pad "59" smd rect
			(at -2.050034 -14.025118 270)
			(size 0.519938 1.4986)
			(layers "F.Cu" "F.Mask" "F.Paste")
			(net "GND")
		)
		(pad "60" smd rect
			(at -2.050034 -13.17498 270)
			(size 0.519938 1.4986)
			(layers "F.Cu" "F.Mask" "F.Paste")
			(net "M_G_CPU0_SA_CB<5>")
		)
		(pad "61" smd rect
			(at -2.050034 -12.325096 270)
			(size 0.519938 1.4986)
			(layers "F.Cu" "F.Mask" "F.Paste")
			(net "GND")
		)
		(pad "62" smd rect
			(at -2.050034 -11.474958 270)
			(size 0.519938 1.4986)
			(layers "F.Cu" "F.Mask" "F.Paste")
			(net "M_G_CPU0_ALERT_N")
		)
		(pad "63" smd rect
			(at -2.050034 -10.625074 270)
			(size 0.519938 1.4986)
			(layers "F.Cu" "F.Mask" "F.Paste")
			(net "GND")
		)
		(pad "64" smd rect
			(at -2.050034 -9.774936 270)
			(size 0.519938 1.4986)
			(layers "F.Cu" "F.Mask" "F.Paste")
			(net "M_G_CPU0_SA_CS_N<0>")
		)
		(pad "65" smd rect
			(at -2.050034 -8.925052 270)
			(size 0.519938 1.4986)
			(layers "F.Cu" "F.Mask" "F.Paste")
			(net "GND")
		)
		(pad "66" smd rect
			(at -2.050034 -8.074914 270)
			(size 0.519938 1.4986)
			(layers "F.Cu" "F.Mask" "F.Paste")
			(net "M_G_CPU0_SA_CA<0>")
		)
		(pad "67" smd rect
			(at -2.050034 -7.22503 270)
			(size 0.519938 1.4986)
			(layers "F.Cu" "F.Mask" "F.Paste")
			(net "GND")
		)
		(pad "68" smd rect
			(at -2.050034 -6.374892 270)
			(size 0.519938 1.4986)
			(layers "F.Cu" "F.Mask" "F.Paste")
			(net "M_G_CPU0_SA_CA<2>")
		)
		(pad "69" smd rect
			(at -2.050034 -5.525008 270)
			(size 0.519938 1.4986)
			(layers "F.Cu" "F.Mask" "F.Paste")
			(net "GND")
		)
		(pad "70" smd rect
			(at -2.050034 -4.675124 270)
			(size 0.519938 1.4986)
			(layers "F.Cu" "F.Mask" "F.Paste")
			(net "M_G_CPU0_SA_CA<4>")
		)
		(pad "71" smd rect
			(at -2.050034 -3.824986 270)
			(size 0.519938 1.4986)
			(layers "F.Cu" "F.Mask" "F.Paste")
			(net "GND")
		)
		(pad "72" smd rect
			(at -2.050034 -2.975102 270)
			(size 0.519938 1.4986)
			(layers "F.Cu" "F.Mask" "F.Paste")
			(net "M_G_CPU0_SA_CA<6>")
		)
		(pad "73" smd rect
			(at -2.050034 -2.124964 270)
			(size 0.519938 1.4986)
			(layers "F.Cu" "F.Mask" "F.Paste")
			(net "GND")
		)
		(pad "74" smd rect
			(at -2.050034 -1.27508 270)
			(size 0.519938 1.4986)
			(layers "F.Cu" "F.Mask" "F.Paste")
			(net "M_G_CPU0_SA_PAR")
		)
		(pad "75" smd rect
			(at -2.050034 -0.424942 270)
			(size 0.519938 1.4986)
			(layers "F.Cu" "F.Mask" "F.Paste")
			(net "GND")
		)
		(pad "76" smd rect
			(at -2.050034 5.525008 270)
			(size 0.519938 1.4986)
			(layers "F.Cu" "F.Mask" "F.Paste")
			(net "M_G_CPU0_SB_CA<0>")
		)
		(pad "77" smd rect
			(at -2.050034 6.374892 270)
			(size 0.519938 1.4986)
			(layers "F.Cu" "F.Mask" "F.Paste")
			(net "GND")
		)
		(pad "78" smd rect
			(at -2.050034 7.22503 270)
			(size 0.519938 1.4986)
			(layers "F.Cu" "F.Mask" "F.Paste")
			(net "M_G_CPU0_SB_CA<2>")
		)
		(pad "79" smd rect
			(at -2.050034 8.074914 270)
			(size 0.519938 1.4986)
			(layers "F.Cu" "F.Mask" "F.Paste")
			(net "GND")
		)
		(pad "80" smd rect
			(at -2.050034 8.925052 270)
			(size 0.519938 1.4986)
			(layers "F.Cu" "F.Mask" "F.Paste")
			(net "M_G_CPU0_SB_CA<4>")
		)
		(pad "81" smd rect
			(at -2.050034 9.774936 270)
			(size 0.519938 1.4986)
			(layers "F.Cu" "F.Mask" "F.Paste")
			(net "GND")
		)
		(pad "82" smd rect
			(at -2.050034 10.625074 270)
			(size 0.519938 1.4986)
			(layers "F.Cu" "F.Mask" "F.Paste")
			(net "M_G_CPU0_SB_CA<6>")
		)
		(pad "83" smd rect
			(at -2.050034 11.474958 270)
			(size 0.519938 1.4986)
			(layers "F.Cu" "F.Mask" "F.Paste")
			(net "GND")
		)
		(pad "84" smd rect
			(at -2.050034 12.325096 270)
			(size 0.519938 1.4986)
			(layers "F.Cu" "F.Mask" "F.Paste")
			(net "M_G_CPU0_SB_CS_N<0>")
		)
		(pad "85" smd rect
			(at -2.050034 13.17498 270)
			(size 0.519938 1.4986)
			(layers "F.Cu" "F.Mask" "F.Paste")
			(net "GND")
		)
		(pad "86" smd rect
			(at -2.050034 14.025118 270)
			(size 0.519938 1.4986)
			(layers "F.Cu" "F.Mask" "F.Paste")
			(net "M_G_CPU0_SA_RSP<0>")
		)
		(pad "87" smd rect
			(at -2.050034 14.875002 270)
			(size 0.519938 1.4986)
			(layers "F.Cu" "F.Mask" "F.Paste")
			(net "M_G_CPU0_SB_RSP<0>")
		)
		(pad "88" smd rect
			(at -2.050034 15.724886 270)
			(size 0.519938 1.4986)
			(layers "F.Cu" "F.Mask" "F.Paste")
			(net "GND")
		)
		(pad "89" smd rect
			(at -2.050034 16.575024 270)
			(size 0.519938 1.4986)
			(layers "F.Cu" "F.Mask" "F.Paste")
			(net "M_G_CPU0_SB_CB<4>")
		)
		(pad "90" smd rect
			(at -2.050034 17.424908 270)
			(size 0.519938 1.4986)
			(layers "F.Cu" "F.Mask" "F.Paste")
			(net "GND")
		)
		(pad "91" smd rect
			(at -2.050034 18.275046 270)
			(size 0.519938 1.4986)
			(layers "F.Cu" "F.Mask" "F.Paste")
			(net "M_G_CPU0_SB_CB<5>")
		)
		(pad "92" smd rect
			(at -2.050034 19.12493 270)
			(size 0.519938 1.4986)
			(layers "F.Cu" "F.Mask" "F.Paste")
			(net "GND")
		)
		(pad "93" smd rect
			(at -2.050034 19.975068 270)
			(size 0.519938 1.4986)
			(layers "F.Cu" "F.Mask" "F.Paste")
			(net "M_G_CPU0_SB_DQS_DP<9>")
		)
		(pad "94" smd rect
			(at -2.050034 20.824952 270)
			(size 0.519938 1.4986)
			(layers "F.Cu" "F.Mask" "F.Paste")
			(net "M_G_CPU0_SB_DQS_DN<9>")
		)
		(pad "95" smd rect
			(at -2.050034 21.67509 270)
			(size 0.519938 1.4986)
			(layers "F.Cu" "F.Mask" "F.Paste")
			(net "GND")
		)
		(pad "96" smd rect
			(at -2.050034 22.524974 270)
			(size 0.519938 1.4986)
			(layers "F.Cu" "F.Mask" "F.Paste")
			(net "M_G_CPU0_SB_CB<0>")
		)
		(pad "97" smd rect
			(at -2.050034 23.375112 270)
			(size 0.519938 1.4986)
			(layers "F.Cu" "F.Mask" "F.Paste")
			(net "GND")
		)
		(pad "98" smd rect
			(at -2.050034 24.224996 270)
			(size 0.519938 1.4986)
			(layers "F.Cu" "F.Mask" "F.Paste")
			(net "M_G_CPU0_SB_CB<1>")
		)
		(pad "99" smd rect
			(at -2.050034 25.07488 270)
			(size 0.519938 1.4986)
			(layers "F.Cu" "F.Mask" "F.Paste")
			(net "GND")
		)
		(pad "100" smd rect
			(at -2.050034 25.925018 270)
			(size 0.519938 1.4986)
			(layers "F.Cu" "F.Mask" "F.Paste")
			(net "M_G_CPU0_SB_DQ<0>")
		)
		(pad "101" smd rect
			(at -2.050034 26.774902 270)
			(size 0.519938 1.4986)
			(layers "F.Cu" "F.Mask" "F.Paste")
			(net "GND")
		)
		(pad "102" smd rect
			(at -2.050034 27.62504 270)
			(size 0.519938 1.4986)
			(layers "F.Cu" "F.Mask" "F.Paste")
			(net "M_G_CPU0_SB_DQ<1>")
		)
		(pad "103" smd rect
			(at -2.050034 28.474924 270)
			(size 0.519938 1.4986)
			(layers "F.Cu" "F.Mask" "F.Paste")
			(net "GND")
		)
		(pad "104" smd rect
			(at -2.050034 29.325062 270)
			(size 0.519938 1.4986)
			(layers "F.Cu" "F.Mask" "F.Paste")
			(net "M_G_CPU0_SB_DQS_DP<0>")
		)
		(pad "105" smd rect
			(at -2.050034 30.174946 270)
			(size 0.519938 1.4986)
			(layers "F.Cu" "F.Mask" "F.Paste")
			(net "M_G_CPU0_SB_DQS_DN<0>")
		)
		(pad "106" smd rect
			(at -2.050034 31.025084 270)
			(size 0.519938 1.4986)
			(layers "F.Cu" "F.Mask" "F.Paste")
			(net "GND")
		)
		(pad "107" smd rect
			(at -2.050034 31.874968 270)
			(size 0.519938 1.4986)
			(layers "F.Cu" "F.Mask" "F.Paste")
			(net "M_G_CPU0_SB_DQ<4>")
		)
		(pad "108" smd rect
			(at -2.050034 32.725106 270)
			(size 0.519938 1.4986)
			(layers "F.Cu" "F.Mask" "F.Paste")
			(net "GND")
		)
		(pad "109" smd rect
			(at -2.050034 33.57499 270)
			(size 0.519938 1.4986)
			(layers "F.Cu" "F.Mask" "F.Paste")
			(net "M_G_CPU0_SB_DQ<5>")
		)
		(pad "110" smd rect
			(at -2.050034 34.425128 270)
			(size 0.519938 1.4986)
			(layers "F.Cu" "F.Mask" "F.Paste")
			(net "GND")
		)
		(pad "111" smd rect
			(at -2.050034 35.275012 270)
			(size 0.519938 1.4986)
			(layers "F.Cu" "F.Mask" "F.Paste")
			(net "M_G_CPU0_SB_DQ<8>")
		)
		(pad "112" smd rect
			(at -2.050034 36.124896 270)
			(size 0.519938 1.4986)
			(layers "F.Cu" "F.Mask" "F.Paste")
			(net "GND")
		)
	)
)
